(kicad_pcb
	(version 20260206)
	(generator "pcbnew")
	(generator_version "10.0")
	(general
		(thickness 1.6)
		(legacy_teardrops no)
	)
	(paper "A4")
	(title_block
		(title "04192023_DAF0TMB3IC0_F0TG_MB_C_brd_V02_OCP.brd")
		(comment 1 "Grand Teton / footprints 7279-7287 of 8354")
	)
	(layers
		(0 "F.Cu" signal "TOP")
		(4 "In1.Cu" signal "GND")
		(6 "In2.Cu" signal "IN1")
		(8 "In3.Cu" signal "GND1")
		(10 "In4.Cu" signal "IN2")
		(12 "In5.Cu" signal "GND2")
		(14 "In6.Cu" signal "IN3")
		(16 "In7.Cu" signal "GND3")
		(18 "In8.Cu" signal "VCC")
		(20 "In9.Cu" signal "VCC1")
		(22 "In10.Cu" signal "GND4")
		(24 "In11.Cu" signal "IN4")
		(26 "In12.Cu" signal "GND5")
		(28 "In13.Cu" signal "IN5")
		(30 "In14.Cu" signal "GND6")
		(32 "In15.Cu" signal "IN6")
		(34 "In16.Cu" signal "GND7")
		(2 "B.Cu" signal "BOTTOM")
		(9 "F.Adhes" user "F.Adhesive")
		(11 "B.Adhes" user "B.Adhesive")
		(13 "F.Paste" user "Package Geometry/Pastemask Top")
		(15 "B.Paste" user "Package Geometry/Pastemask Bottom")
		(5 "F.SilkS" user "Ref Des/Silkscreen Top")
		(7 "B.SilkS" user "Ref Des/Silkscreen Bottom")
		(1 "F.Mask" user "Board Geometry/Soldermask Top")
		(3 "B.Mask" user "Board Geometry/Soldermask Bottom")
		(17 "Dwgs.User" user "User.Drawings")
		(19 "Cmts.User" user "User.Comments")
		(21 "Eco1.User" user "User.Eco1")
		(23 "Eco2.User" user "User.Eco2")
		(25 "Edge.Cuts" user "Board Geometry/Outline")
		(27 "Margin" user)
		(31 "F.CrtYd" user "Package Geometry/Place Bound Top")
		(29 "B.CrtYd" user "Package Geometry/Place Bound Bottom")
		(35 "F.Fab" user "Ref Des/Assembly Top")
		(33 "B.Fab" user "Ref Des/Assembly Bottom")
	)
	(footprint ""
		(layer "B.Cu")
		(at 53.084476 -339.890354 -90)
		(property "Reference" "PC450"
			(at 9.660636 -0.954786 270)
			(unlocked yes)
			(layer "B.SilkS")
			(effects
				(font
					(size 0.7874 0.5842)
					(thickness 0.1524)
				)
				(justify left mirror)
			)
		)
		(property "Value" ""
			(at 0 0 90)
			(layer "B.Fab")
			(effects
				(font
					(size 1.27 1.27)
				)
				(justify mirror)
			)
		)
		(duplicate_pad_numbers_are_jumpers no)
		(fp_line
			(start -4.533392 2.249932)
			(end 4.533392 2.249932)
			(stroke
				(width 0.1524)
				(type default)
			)
			(layer "B.SilkS")
		)
		(fp_line
			(start 4.533392 2.249932)
			(end 4.533392 -2.249932)
			(stroke
				(width 0.1524)
				(type default)
			)
			(layer "B.SilkS")
		)
		(fp_line
			(start -4.533392 -2.249932)
			(end -4.533392 2.249932)
			(stroke
				(width 0.1524)
				(type default)
			)
			(layer "B.SilkS")
		)
		(fp_line
			(start 4.533392 -2.249932)
			(end -4.533392 -2.249932)
			(stroke
				(width 0.1524)
				(type default)
			)
			(layer "B.SilkS")
		)
		(fp_rect
			(start 5.39242 2.326132)
			(end 4.533392 -2.326132)
			(stroke
				(width 0)
				(type default)
			)
			(fill yes)
			(layer "B.SilkS")
		)
		(fp_line
			(start -3.750056 2.249932)
			(end 3.750056 2.249932)
			(stroke
				(width 0.1)
				(type default)
			)
			(layer "B.Fab")
		)
		(fp_line
			(start 3.750056 2.249932)
			(end 3.750056 -2.249932)
			(stroke
				(width 0.1)
				(type default)
			)
			(layer "B.Fab")
		)
		(fp_line
			(start -3.750056 -2.249932)
			(end -3.750056 2.249932)
			(stroke
				(width 0.1)
				(type default)
			)
			(layer "B.Fab")
		)
		(fp_line
			(start 3.750056 -2.249932)
			(end -3.750056 -2.249932)
			(stroke
				(width 0.1)
				(type default)
			)
			(layer "B.Fab")
		)
		(fp_text user "-"
			(at -4.543044 1.90627 270)
			(unlocked yes)
			(layer "B.SilkS")
			(effects
				(font
					(size 1.905 1.4224)
					(thickness 0.1524)
				)
				(justify left mirror)
			)
		)
		(fp_text user "+"
			(at 6.483604 0.760476 180)
			(unlocked yes)
			(layer "B.SilkS")
			(effects
				(font
					(size 1.905 1.4224)
					(thickness 0.1524)
				)
				(justify left mirror)
			)
		)
		(fp_text user "+"
			(at 6.322314 0.786384 180)
			(unlocked yes)
			(layer "B.Fab")
			(effects
				(font
					(size 1.905 1.4224)
					(thickness 0.1524)
				)
				(justify left mirror)
			)
		)
		(fp_text user "-"
			(at -4.8514 -0.14605 270)
			(unlocked yes)
			(layer "B.Fab")
			(effects
				(font
					(size 1.905 1.4224)
					(thickness 0.1524)
				)
				(justify left mirror)
			)
		)
		(pad "1" smd rect
			(at 3.199892 0 90)
			(size 2.413 2.8194)
			(layers "B.Cu" "B.Mask" "B.Paste")
			(net "PVDDIO_P1")
		)
		(pad "2" smd rect
			(at -3.199892 0 90)
			(size 2.413 2.8194)
			(layers "B.Cu" "B.Mask" "B.Paste")
			(net "GND")
		)
	)
	(footprint ""
		(layer "B.Cu")
		(at 365.846868 -423.022776 180)
		(property "Reference" "R838"
			(at 0 0 0)
			(layer "B.SilkS")
			(hide yes)
			(effects
				(font
					(size 1.27 1.27)
				)
				(justify mirror)
			)
		)
		(property "Value" ""
			(at 0 0 0)
			(layer "B.Fab")
			(effects
				(font
					(size 1.27 1.27)
				)
				(justify mirror)
			)
		)
		(duplicate_pad_numbers_are_jumpers no)
		(fp_line
			(start 0.32512 0.175006)
			(end 0.32512 -0.175006)
			(stroke
				(width 0.1)
				(type default)
			)
			(layer "B.Fab")
		)
		(fp_line
			(start 0.32512 -0.175006)
			(end -0.32512 -0.175006)
			(stroke
				(width 0.1)
				(type default)
			)
			(layer "B.Fab")
		)
		(fp_line
			(start -0.32512 0.175006)
			(end 0.32512 0.175006)
			(stroke
				(width 0.1)
				(type default)
			)
			(layer "B.Fab")
		)
		(fp_line
			(start -0.32512 -0.175006)
			(end -0.32512 0.175006)
			(stroke
				(width 0.1)
				(type default)
			)
			(layer "B.Fab")
		)
		(pad "1" smd rect
			(at 0.2667 0)
			(size 0.3048 0.381)
			(layers "B.Cu" "B.Mask" "B.Paste")
			(net "P1V8_CPU0_RT_1D")
		)
		(pad "2" smd rect
			(at -0.2667 0 180)
			(size 0.3048 0.381)
			(layers "B.Cu" "B.Mask" "B.Paste")
			(net "SMB_RT_CPU0_P3_ROM_R_SDA")
		)
	)
	(footprint ""
		(layer "B.Cu")
		(at 357.835454 -250.25731)
		(property "Reference" "C279"
			(at 0 0 0)
			(layer "B.SilkS")
			(hide yes)
			(effects
				(font
					(size 1.27 1.27)
				)
				(justify mirror)
			)
		)
		(property "Value" ""
			(at 0 0 0)
			(layer "B.Fab")
			(effects
				(font
					(size 1.27 1.27)
				)
				(justify mirror)
			)
		)
		(duplicate_pad_numbers_are_jumpers no)
		(fp_line
			(start -0.7874 -0.4064)
			(end -0.7874 0.4064)
			(stroke
				(width 0.1524)
				(type default)
			)
			(layer "B.SilkS")
		)
		(fp_line
			(start -0.7874 0.4064)
			(end 0.7874 0.4064)
			(stroke
				(width 0.1524)
				(type default)
			)
			(layer "B.SilkS")
		)
		(fp_line
			(start 0.7874 -0.4064)
			(end -0.7874 -0.4064)
			(stroke
				(width 0.1524)
				(type default)
			)
			(layer "B.SilkS")
		)
		(fp_line
			(start 0.7874 0.4064)
			(end 0.7874 -0.4064)
			(stroke
				(width 0.1524)
				(type default)
			)
			(layer "B.SilkS")
		)
		(fp_line
			(start -0.67945 -0.3048)
			(end -0.67945 0.3048)
			(stroke
				(width 0.1)
				(type default)
			)
			(layer "B.Fab")
		)
		(fp_line
			(start -0.67945 0.3048)
			(end -0.120396 0.3048)
			(stroke
				(width 0.1)
				(type default)
			)
			(layer "B.Fab")
		)
		(fp_line
			(start -0.12065 -0.3048)
			(end -0.67945 -0.3048)
			(stroke
				(width 0.1)
				(type default)
			)
			(layer "B.Fab")
		)
		(fp_line
			(start -0.12065 -0.2794)
			(end -0.12065 -0.3048)
			(stroke
				(width 0.1)
				(type default)
			)
			(layer "B.Fab")
		)
		(fp_line
			(start -0.120396 0.2794)
			(end 0.12065 0.2794)
			(stroke
				(width 0.1)
				(type default)
			)
			(layer "B.Fab")
		)
		(fp_line
			(start -0.120396 0.3048)
			(end -0.120396 0.2794)
			(stroke
				(width 0.1)
				(type default)
			)
			(layer "B.Fab")
		)
		(fp_line
			(start 0.12065 -0.305054)
			(end 0.12065 -0.2794)
			(stroke
				(width 0.1)
				(type default)
			)
			(layer "B.Fab")
		)
		(fp_line
			(start 0.12065 -0.2794)
			(end -0.12065 -0.2794)
			(stroke
				(width 0.1)
				(type default)
			)
			(layer "B.Fab")
		)
		(fp_line
			(start 0.12065 0.2794)
			(end 0.12065 0.3048)
			(stroke
				(width 0.1)
				(type default)
			)
			(layer "B.Fab")
		)
		(fp_line
			(start 0.12065 0.3048)
			(end 0.67945 0.3048)
			(stroke
				(width 0.1)
				(type default)
			)
			(layer "B.Fab")
		)
		(fp_line
			(start 0.67945 -0.305054)
			(end 0.12065 -0.305054)
			(stroke
				(width 0.1)
				(type default)
			)
			(layer "B.Fab")
		)
		(fp_line
			(start 0.67945 0.3048)
			(end 0.67945 -0.305054)
			(stroke
				(width 0.1)
				(type default)
			)
			(layer "B.Fab")
		)
		(pad "1" smd circle
			(at 0.40005 0 180)
			(size 0 0)
			(layers "B.Cu" "B.Mask" "B.Paste")
			(net "PVDDCR_CPU0_P0")
		)
		(pad "2" smd circle
			(at -0.40005 0 180)
			(size 0 0)
			(layers "B.Cu" "B.Mask" "B.Paste")
			(net "GND")
		)
	)
	(footprint ""
		(layer "B.Cu")
		(at 238.633 -338.455 180)
		(property "Reference" "R806"
			(at 0 0 0)
			(layer "B.SilkS")
			(hide yes)
			(effects
				(font
					(size 1.27 1.27)
				)
				(justify mirror)
			)
		)
		(property "Value" ""
			(at 0 0 0)
			(layer "B.Fab")
			(effects
				(font
					(size 1.27 1.27)
				)
				(justify mirror)
			)
		)
		(duplicate_pad_numbers_are_jumpers no)
		(fp_line
			(start 0.32512 0.175006)
			(end 0.32512 -0.175006)
			(stroke
				(width 0.1)
				(type default)
			)
			(layer "B.Fab")
		)
		(fp_line
			(start 0.32512 -0.175006)
			(end -0.32512 -0.175006)
			(stroke
				(width 0.1)
				(type default)
			)
			(layer "B.Fab")
		)
		(fp_line
			(start -0.32512 0.175006)
			(end 0.32512 0.175006)
			(stroke
				(width 0.1)
				(type default)
			)
			(layer "B.Fab")
		)
		(fp_line
			(start -0.32512 -0.175006)
			(end -0.32512 0.175006)
			(stroke
				(width 0.1)
				(type default)
			)
			(layer "B.Fab")
		)
		(pad "1" smd rect
			(at 0.2667 0)
			(size 0.3048 0.381)
			(layers "B.Cu" "B.Mask" "B.Paste")
			(net "SMB_RT_CPU1_P3_ROM_MUX_2D_SDA")
		)
		(pad "2" smd rect
			(at -0.2667 0 180)
			(size 0.3048 0.381)
			(layers "B.Cu" "B.Mask" "B.Paste")
			(net "SMB_RT_CPU1_P3_ROM_MUX_2D_R_SDA")
		)
	)
	(footprint ""
		(layer "B.Cu")
		(at 344.511884 -338.964016 -90)
		(property "Reference" "PC136_5"
			(at 0 0 90)
			(layer "B.SilkS")
			(hide yes)
			(effects
				(font
					(size 1.27 1.27)
				)
				(justify mirror)
			)
		)
		(property "Value" ""
			(at 0 0 90)
			(layer "B.Fab")
			(effects
				(font
					(size 1.27 1.27)
				)
				(justify mirror)
			)
		)
		(duplicate_pad_numbers_are_jumpers no)
		(fp_line
			(start -1.524 0.762)
			(end 1.524 0.762)
			(stroke
				(width 0.1524)
				(type default)
			)
			(layer "B.SilkS")
		)
		(fp_line
			(start 1.524 0.762)
			(end 1.524 -0.762)
			(stroke
				(width 0.1524)
				(type default)
			)
			(layer "B.SilkS")
		)
		(fp_line
			(start -1.524 -0.762)
			(end -1.524 0.762)
			(stroke
				(width 0.1524)
				(type default)
			)
			(layer "B.SilkS")
		)
		(fp_line
			(start 1.524 -0.762)
			(end -1.524 -0.762)
			(stroke
				(width 0.1524)
				(type default)
			)
			(layer "B.SilkS")
		)
		(fp_line
			(start -1.1049 0.724916)
			(end -1.1049 -0.724916)
			(stroke
				(width 0.1)
				(type default)
			)
			(layer "B.Fab")
		)
		(fp_line
			(start 1.1049 0.724916)
			(end -1.1049 0.724916)
			(stroke
				(width 0.1)
				(type default)
			)
			(layer "B.Fab")
		)
		(fp_line
			(start -1.1049 -0.724916)
			(end 1.1049 -0.724916)
			(stroke
				(width 0.1)
				(type default)
			)
			(layer "B.Fab")
		)
		(fp_line
			(start 1.1049 -0.724916)
			(end 1.1049 0.724916)
			(stroke
				(width 0.1)
				(type default)
			)
			(layer "B.Fab")
		)
		(pad "1" smd rect
			(at 0.889 0 270)
			(size 1.016 1.27)
			(layers "B.Cu" "B.Mask" "B.Paste")
			(net "SW_P12V_AUX_PVDDCR_CPU1_P0_FLT")
		)
		(pad "2" smd rect
			(at -0.889 0 270)
			(size 1.016 1.27)
			(layers "B.Cu" "B.Mask" "B.Paste")
			(net "GND")
		)
	)
	(footprint ""
		(layer "B.Cu")
		(at 172.456094 -414.792668 180)
		(property "Reference" "R2815"
			(at 0 0 0)
			(layer "B.SilkS")
			(hide yes)
			(effects
				(font
					(size 1.27 1.27)
				)
				(justify mirror)
			)
		)
		(property "Value" ""
			(at 0 0 0)
			(layer "B.Fab")
			(effects
				(font
					(size 1.27 1.27)
				)
				(justify mirror)
			)
		)
		(duplicate_pad_numbers_are_jumpers no)
		(fp_line
			(start 0.7874 0.4064)
			(end 0.7874 -0.4064)
			(stroke
				(width 0.1524)
				(type default)
			)
			(layer "B.SilkS")
		)
		(fp_line
			(start 0.7874 -0.4064)
			(end -0.7874 -0.4064)
			(stroke
				(width 0.1524)
				(type default)
			)
			(layer "B.SilkS")
		)
		(fp_line
			(start -0.7874 0.4064)
			(end 0.7874 0.4064)
			(stroke
				(width 0.1524)
				(type default)
			)
			(layer "B.SilkS")
		)
		(fp_line
			(start -0.7874 -0.4064)
			(end -0.7874 0.4064)
			(stroke
				(width 0.1524)
				(type default)
			)
			(layer "B.SilkS")
		)
		(fp_line
			(start 0.67945 0.3048)
			(end 0.67945 -0.305054)
			(stroke
				(width 0.1)
				(type default)
			)
			(layer "B.Fab")
		)
		(fp_line
			(start 0.67945 -0.305054)
			(end 0.12065 -0.305054)
			(stroke
				(width 0.1)
				(type default)
			)
			(layer "B.Fab")
		)
		(fp_line
			(start 0.12065 0.3048)
			(end 0.67945 0.3048)
			(stroke
				(width 0.1)
				(type default)
			)
			(layer "B.Fab")
		)
		(fp_line
			(start 0.12065 0.2794)
			(end 0.12065 0.3048)
			(stroke
				(width 0.1)
				(type default)
			)
			(layer "B.Fab")
		)
		(fp_line
			(start 0.12065 -0.2794)
			(end -0.12065 -0.2794)
			(stroke
				(width 0.1)
				(type default)
			)
			(layer "B.Fab")
		)
		(fp_line
			(start 0.12065 -0.305054)
			(end 0.12065 -0.2794)
			(stroke
				(width 0.1)
				(type default)
			)
			(layer "B.Fab")
		)
		(fp_line
			(start -0.120396 0.3048)
			(end -0.120396 0.2794)
			(stroke
				(width 0.1)
				(type default)
			)
			(layer "B.Fab")
		)
		(fp_line
			(start -0.120396 0.2794)
			(end 0.12065 0.2794)
			(stroke
				(width 0.1)
				(type default)
			)
			(layer "B.Fab")
		)
		(fp_line
			(start -0.12065 -0.2794)
			(end -0.12065 -0.3048)
			(stroke
				(width 0.1)
				(type default)
			)
			(layer "B.Fab")
		)
		(fp_line
			(start -0.12065 -0.3048)
			(end -0.67945 -0.3048)
			(stroke
				(width 0.1)
				(type default)
			)
			(layer "B.Fab")
		)
		(fp_line
			(start -0.67945 0.3048)
			(end -0.120396 0.3048)
			(stroke
				(width 0.1)
				(type default)
			)
			(layer "B.Fab")
		)
		(fp_line
			(start -0.67945 -0.3048)
			(end -0.67945 0.3048)
			(stroke
				(width 0.1)
				(type default)
			)
			(layer "B.Fab")
		)
		(pad "1" smd circle
			(at 0.40005 0)
			(size 0 0)
			(layers "B.Cu" "B.Mask" "B.Paste")
			(net "P3V3_AUX")
		)
		(pad "2" smd circle
			(at -0.40005 0)
			(size 0 0)
			(layers "B.Cu" "B.Mask" "B.Paste")
			(net "BMC_MONITER_R")
		)
	)
	(footprint ""
		(layer "B.Cu")
		(at 405.546306 -396.393162 -90)
		(property "Reference" "C972"
			(at 0 0 90)
			(layer "B.SilkS")
			(hide yes)
			(effects
				(font
					(size 1.27 1.27)
				)
				(justify mirror)
			)
		)
		(property "Value" ""
			(at 0 0 90)
			(layer "B.Fab")
			(effects
				(font
					(size 1.27 1.27)
				)
				(justify mirror)
			)
		)
		(duplicate_pad_numbers_are_jumpers no)
		(fp_line
			(start -0.299974 0.150114)
			(end 0.299974 0.150114)
			(stroke
				(width 0.1)
				(type default)
			)
			(layer "B.Fab")
		)
		(fp_line
			(start 0.299974 0.150114)
			(end 0.299974 -0.150114)
			(stroke
				(width 0.1)
				(type default)
			)
			(layer "B.Fab")
		)
		(fp_line
			(start -0.299974 -0.150114)
			(end -0.299974 0.150114)
			(stroke
				(width 0.1)
				(type default)
			)
			(layer "B.Fab")
		)
		(fp_line
			(start 0.299974 -0.150114)
			(end -0.299974 -0.150114)
			(stroke
				(width 0.1)
				(type default)
			)
			(layer "B.Fab")
		)
		(pad "1" smd rect
			(at 0.2667 0 90)
			(size 0.3048 0.381)
			(layers "B.Cu" "B.Mask" "B.Paste")
			(net "P0V9_CPU0_RT2_2A")
		)
		(pad "2" smd rect
			(at -0.2667 0 90)
			(size 0.3048 0.381)
			(layers "B.Cu" "B.Mask" "B.Paste")
			(net "GND")
		)
	)
	(footprint ""
		(layer "B.Cu")
		(at 254.635 -341.884 180)
		(property "Reference" "R1366"
			(at 0 0 0)
			(layer "B.SilkS")
			(hide yes)
			(effects
				(font
					(size 1.27 1.27)
				)
				(justify mirror)
			)
		)
		(property "Value" ""
			(at 0 0 0)
			(layer "B.Fab")
			(effects
				(font
					(size 1.27 1.27)
				)
				(justify mirror)
			)
		)
		(duplicate_pad_numbers_are_jumpers no)
		(fp_line
			(start 0.32512 0.175006)
			(end 0.32512 -0.175006)
			(stroke
				(width 0.1)
				(type default)
			)
			(layer "B.Fab")
		)
		(fp_line
			(start 0.32512 -0.175006)
			(end -0.32512 -0.175006)
			(stroke
				(width 0.1)
				(type default)
			)
			(layer "B.Fab")
		)
		(fp_line
			(start -0.32512 0.175006)
			(end 0.32512 0.175006)
			(stroke
				(width 0.1)
				(type default)
			)
			(layer "B.Fab")
		)
		(fp_line
			(start -0.32512 -0.175006)
			(end -0.32512 0.175006)
			(stroke
				(width 0.1)
				(type default)
			)
			(layer "B.Fab")
		)
		(pad "1" smd rect
			(at 0.2667 0)
			(size 0.3048 0.381)
			(layers "B.Cu" "B.Mask" "B.Paste")
			(net "P1V8_CPU0_RT_1D")
		)
		(pad "2" smd rect
			(at -0.2667 0 180)
			(size 0.3048 0.381)
			(layers "B.Cu" "B.Mask" "B.Paste")
			(net "SMB_RT_CPU0_P0_ROM_MUX_2D_R_SDA")
		)
	)
	(footprint ""
		(layer "B.Cu")
		(at 85.94598 -180.078634 90)
		(property "Reference" "PR191"
			(at 0 0 90)
			(layer "B.SilkS")
			(hide yes)
			(effects
				(font
					(size 1.27 1.27)
				)
				(justify mirror)
			)
		)
		(property "Value" ""
			(at 0 0 90)
			(layer "B.Fab")
			(effects
				(font
					(size 1.27 1.27)
				)
				(justify mirror)
			)
		)
		(duplicate_pad_numbers_are_jumpers no)
		(fp_line
			(start 0.7874 -0.4064)
			(end -0.7874 -0.4064)
			(stroke
				(width 0.1524)
				(type default)
			)
			(layer "B.SilkS")
		)
		(fp_line
			(start -0.7874 -0.4064)
			(end -0.7874 0.4064)
			(stroke
				(width 0.1524)
				(type default)
			)
			(layer "B.SilkS")
		)
		(fp_line
			(start 0.7874 0.4064)
			(end 0.7874 -0.4064)
			(stroke
				(width 0.1524)
				(type default)
			)
			(layer "B.SilkS")
		)
		(fp_line
			(start -0.7874 0.4064)
			(end 0.7874 0.4064)
			(stroke
				(width 0.1524)
				(type default)
			)
			(layer "B.SilkS")
		)
		(fp_line
			(start 0.67945 -0.305054)
			(end 0.12065 -0.305054)
			(stroke
				(width 0.1)
				(type default)
			)
			(layer "B.Fab")
		)
		(fp_line
			(start 0.12065 -0.305054)
			(end 0.12065 -0.2794)
			(stroke
				(width 0.1)
				(type default)
			)
			(layer "B.Fab")
		)
		(fp_line
			(start -0.12065 -0.3048)
			(end -0.67945 -0.3048)
			(stroke
				(width 0.1)
				(type default)
			)
			(layer "B.Fab")
		)
		(fp_line
			(start -0.67945 -0.3048)
			(end -0.67945 0.3048)
			(stroke
				(width 0.1)
				(type default)
			)
			(layer "B.Fab")
		)
		(fp_line
			(start 0.12065 -0.2794)
			(end -0.12065 -0.2794)
			(stroke
				(width 0.1)
				(type default)
			)
			(layer "B.Fab")
		)
		(fp_line
			(start -0.12065 -0.2794)
			(end -0.12065 -0.3048)
			(stroke
				(width 0.1)
				(type default)
			)
			(layer "B.Fab")
		)
		(fp_line
			(start 0.12065 0.2794)
			(end 0.12065 0.3048)
			(stroke
				(width 0.1)
				(type default)
			)
			(layer "B.Fab")
		)
		(fp_line
			(start -0.120396 0.2794)
			(end 0.12065 0.2794)
			(stroke
				(width 0.1)
				(type default)
			)
			(layer "B.Fab")
		)
		(fp_line
			(start 0.67945 0.3048)
			(end 0.67945 -0.305054)
			(stroke
				(width 0.1)
				(type default)
			)
			(layer "B.Fab")
		)
		(fp_line
			(start 0.12065 0.3048)
			(end 0.67945 0.3048)
			(stroke
				(width 0.1)
				(type default)
			)
			(layer "B.Fab")
		)
		(fp_line
			(start -0.120396 0.3048)
			(end -0.120396 0.2794)
			(stroke
				(width 0.1)
				(type default)
			)
			(layer "B.Fab")
		)
		(fp_line
			(start -0.67945 0.3048)
			(end -0.120396 0.3048)
			(stroke
				(width 0.1)
				(type default)
			)
			(layer "B.Fab")
		)
		(pad "1" smd circle
			(at 0.40005 0 270)
			(size 0 0)
			(layers "B.Cu" "B.Mask" "B.Paste")
			(net "PVDDCR_CPU0_P1_VOS1")
		)
		(pad "2" smd circle
			(at -0.40005 0 270)
			(size 0 0)
			(layers "B.Cu" "B.Mask" "B.Paste")
			(net "PVDDCR_CPU0_P1")
		)
	)
)
